(kicad_pcb
	(version 20260206)
	(generator "pcbnew")
	(generator_version "10.0")
	(general
		(thickness 1.6)
		(legacy_teardrops no)
	)
	(paper "A4")
	(title_block
		(title "04192023_DAF0TMB3IC0_F0TG_MB_C_brd_V02_OCP.brd")
		(comment 1 "Grand Teton / footprints 4995-5001 of 8354")
	)
	(layers
		(0 "F.Cu" signal "TOP")
		(4 "In1.Cu" signal "GND")
		(6 "In2.Cu" signal "IN1")
		(8 "In3.Cu" signal "GND1")
		(10 "In4.Cu" signal "IN2")
		(12 "In5.Cu" signal "GND2")
		(14 "In6.Cu" signal "IN3")
		(16 "In7.Cu" signal "GND3")
		(18 "In8.Cu" signal "VCC")
		(20 "In9.Cu" signal "VCC1")
		(22 "In10.Cu" signal "GND4")
		(24 "In11.Cu" signal "IN4")
		(26 "In12.Cu" signal "GND5")
		(28 "In13.Cu" signal "IN5")
		(30 "In14.Cu" signal "GND6")
		(32 "In15.Cu" signal "IN6")
		(34 "In16.Cu" signal "GND7")
		(2 "B.Cu" signal "BOTTOM")
		(9 "F.Adhes" user "F.Adhesive")
		(11 "B.Adhes" user "B.Adhesive")
		(13 "F.Paste" user "Package Geometry/Pastemask Top")
		(15 "B.Paste" user "Package Geometry/Pastemask Bottom")
		(5 "F.SilkS" user "Ref Des/Silkscreen Top")
		(7 "B.SilkS" user "Ref Des/Silkscreen Bottom")
		(1 "F.Mask" user "Board Geometry/Soldermask Top")
		(3 "B.Mask" user "Board Geometry/Soldermask Bottom")
		(17 "Dwgs.User" user "User.Drawings")
		(19 "Cmts.User" user "User.Comments")
		(21 "Eco1.User" user "User.Eco1")
		(23 "Eco2.User" user "User.Eco2")
		(25 "Edge.Cuts" user "Board Geometry/Outline")
		(27 "Margin" user)
		(31 "F.CrtYd" user "Package Geometry/Place Bound Top")
		(29 "B.CrtYd" user "Package Geometry/Place Bound Bottom")
		(35 "F.Fab" user "Ref Des/Assembly Top")
		(33 "B.Fab" user "Ref Des/Assembly Bottom")
	)
	(footprint ""
		(layer "B.Cu")
		(at 208.461356 -381.222504)
		(property "Reference" "PR2517"
			(at 0 0 0)
			(layer "B.SilkS")
			(hide yes)
			(effects
				(font
					(size 1.27 1.27)
				)
				(justify mirror)
			)
		)
		(property "Value" ""
			(at 0 0 0)
			(layer "B.Fab")
			(effects
				(font
					(size 1.27 1.27)
				)
				(justify mirror)
			)
		)
		(duplicate_pad_numbers_are_jumpers no)
		(fp_line
			(start -0.7874 -0.4064)
			(end -0.7874 0.4064)
			(stroke
				(width 0.1524)
				(type default)
			)
			(layer "B.SilkS")
		)
		(fp_line
			(start -0.7874 0.4064)
			(end 0.7874 0.4064)
			(stroke
				(width 0.1524)
				(type default)
			)
			(layer "B.SilkS")
		)
		(fp_line
			(start 0.7874 -0.4064)
			(end -0.7874 -0.4064)
			(stroke
				(width 0.1524)
				(type default)
			)
			(layer "B.SilkS")
		)
		(fp_line
			(start 0.7874 0.4064)
			(end 0.7874 -0.4064)
			(stroke
				(width 0.1524)
				(type default)
			)
			(layer "B.SilkS")
		)
		(fp_line
			(start -0.67945 -0.3048)
			(end -0.67945 0.3048)
			(stroke
				(width 0.1)
				(type default)
			)
			(layer "B.Fab")
		)
		(fp_line
			(start -0.67945 0.3048)
			(end -0.120396 0.3048)
			(stroke
				(width 0.1)
				(type default)
			)
			(layer "B.Fab")
		)
		(fp_line
			(start -0.12065 -0.3048)
			(end -0.67945 -0.3048)
			(stroke
				(width 0.1)
				(type default)
			)
			(layer "B.Fab")
		)
		(fp_line
			(start -0.12065 -0.2794)
			(end -0.12065 -0.3048)
			(stroke
				(width 0.1)
				(type default)
			)
			(layer "B.Fab")
		)
		(fp_line
			(start -0.120396 0.2794)
			(end 0.12065 0.2794)
			(stroke
				(width 0.1)
				(type default)
			)
			(layer "B.Fab")
		)
		(fp_line
			(start -0.120396 0.3048)
			(end -0.120396 0.2794)
			(stroke
				(width 0.1)
				(type default)
			)
			(layer "B.Fab")
		)
		(fp_line
			(start 0.12065 -0.305054)
			(end 0.12065 -0.2794)
			(stroke
				(width 0.1)
				(type default)
			)
			(layer "B.Fab")
		)
		(fp_line
			(start 0.12065 -0.2794)
			(end -0.12065 -0.2794)
			(stroke
				(width 0.1)
				(type default)
			)
			(layer "B.Fab")
		)
		(fp_line
			(start 0.12065 0.2794)
			(end 0.12065 0.3048)
			(stroke
				(width 0.1)
				(type default)
			)
			(layer "B.Fab")
		)
		(fp_line
			(start 0.12065 0.3048)
			(end 0.67945 0.3048)
			(stroke
				(width 0.1)
				(type default)
			)
			(layer "B.Fab")
		)
		(fp_line
			(start 0.67945 -0.305054)
			(end 0.12065 -0.305054)
			(stroke
				(width 0.1)
				(type default)
			)
			(layer "B.Fab")
		)
		(fp_line
			(start 0.67945 0.3048)
			(end 0.67945 -0.305054)
			(stroke
				(width 0.1)
				(type default)
			)
			(layer "B.Fab")
		)
		(pad "1" smd circle
			(at 0.40005 0 180)
			(size 0 0)
			(layers "B.Cu" "B.Mask" "B.Paste")
			(net "P12V_HSC_ADC_N")
		)
		(pad "2" smd circle
			(at -0.40005 0 180)
			(size 0 0)
			(layers "B.Cu" "B.Mask" "B.Paste")
			(net "P12V_HSC_SENSE2_R3_N")
		)
	)
	(footprint ""
		(layer "B.Cu")
		(at 73.248774 -184.343548 90)
		(property "Reference" "PC279"
			(at 5.811012 0.851916 270)
			(unlocked yes)
			(layer "B.SilkS")
			(effects
				(font
					(size 0.7874 0.5842)
					(thickness 0.1524)
				)
				(justify left mirror)
			)
		)
		(property "Value" ""
			(at 0 0 90)
			(layer "B.Fab")
			(effects
				(font
					(size 1.27 1.27)
				)
				(justify mirror)
			)
		)
		(duplicate_pad_numbers_are_jumpers no)
		(fp_line
			(start 4.533392 -2.249932)
			(end -4.533392 -2.249932)
			(stroke
				(width 0.1524)
				(type default)
			)
			(layer "B.SilkS")
		)
		(fp_line
			(start -4.533392 -2.249932)
			(end -4.533392 2.249932)
			(stroke
				(width 0.1524)
				(type default)
			)
			(layer "B.SilkS")
		)
		(fp_line
			(start 4.533392 2.249932)
			(end 4.533392 -2.249932)
			(stroke
				(width 0.1524)
				(type default)
			)
			(layer "B.SilkS")
		)
		(fp_line
			(start -4.533392 2.249932)
			(end 4.533392 2.249932)
			(stroke
				(width 0.1524)
				(type default)
			)
			(layer "B.SilkS")
		)
		(fp_rect
			(start 4.533392 -2.326132)
			(end 5.39242 2.326132)
			(stroke
				(width 0)
				(type default)
			)
			(fill yes)
			(layer "B.SilkS")
		)
		(fp_line
			(start 3.750056 -2.249932)
			(end -3.750056 -2.249932)
			(stroke
				(width 0.1)
				(type default)
			)
			(layer "B.Fab")
		)
		(fp_line
			(start -3.750056 -2.249932)
			(end -3.750056 2.249932)
			(stroke
				(width 0.1)
				(type default)
			)
			(layer "B.Fab")
		)
		(fp_line
			(start 3.750056 2.249932)
			(end 3.750056 -2.249932)
			(stroke
				(width 0.1)
				(type default)
			)
			(layer "B.Fab")
		)
		(fp_line
			(start -3.750056 2.249932)
			(end 3.750056 2.249932)
			(stroke
				(width 0.1)
				(type default)
			)
			(layer "B.Fab")
		)
		(fp_text user "+"
			(at 6.322314 0.786384 0)
			(unlocked yes)
			(layer "B.SilkS")
			(effects
				(font
					(size 1.905 1.4224)
					(thickness 0.1524)
				)
				(justify left mirror)
			)
		)
		(fp_text user "-"
			(at -4.83997 0.996696 90)
			(unlocked yes)
			(layer "B.SilkS")
			(effects
				(font
					(size 1.905 1.4224)
					(thickness 0.1524)
				)
				(justify left mirror)
			)
		)
		(fp_text user "-"
			(at -4.8514 -0.14605 90)
			(unlocked yes)
			(layer "B.Fab")
			(effects
				(font
					(size 1.905 1.4224)
					(thickness 0.1524)
				)
				(justify left mirror)
			)
		)
		(fp_text user "+"
			(at 6.322314 0.786384 0)
			(unlocked yes)
			(layer "B.Fab")
			(effects
				(font
					(size 1.905 1.4224)
					(thickness 0.1524)
				)
				(justify left mirror)
			)
		)
		(pad "1" smd rect
			(at 3.199892 0 270)
			(size 2.413 2.8194)
			(layers "B.Cu" "B.Mask" "B.Paste")
			(net "PVDDCR_CPU0_P1")
		)
		(pad "2" smd rect
			(at -3.199892 0 270)
			(size 2.413 2.8194)
			(layers "B.Cu" "B.Mask" "B.Paste")
			(net "GND")
		)
	)
	(footprint ""
		(layer "B.Cu")
		(at 233.807 -332.74 180)
		(property "Reference" "R6773"
			(at 0 0 0)
			(layer "B.SilkS")
			(hide yes)
			(effects
				(font
					(size 1.27 1.27)
				)
				(justify mirror)
			)
		)
		(property "Value" ""
			(at 0 0 0)
			(layer "B.Fab")
			(effects
				(font
					(size 1.27 1.27)
				)
				(justify mirror)
			)
		)
		(duplicate_pad_numbers_are_jumpers no)
		(fp_line
			(start 0.32512 0.175006)
			(end 0.32512 -0.175006)
			(stroke
				(width 0.1)
				(type default)
			)
			(layer "B.Fab")
		)
		(fp_line
			(start 0.32512 -0.175006)
			(end -0.32512 -0.175006)
			(stroke
				(width 0.1)
				(type default)
			)
			(layer "B.Fab")
		)
		(fp_line
			(start -0.32512 0.175006)
			(end 0.32512 0.175006)
			(stroke
				(width 0.1)
				(type default)
			)
			(layer "B.Fab")
		)
		(fp_line
			(start -0.32512 -0.175006)
			(end -0.32512 0.175006)
			(stroke
				(width 0.1)
				(type default)
			)
			(layer "B.Fab")
		)
		(pad "1" smd rect
			(at 0.2667 0)
			(size 0.3048 0.381)
			(layers "B.Cu" "B.Mask" "B.Paste")
			(net "RT_SMB_MUX_ADDR2")
		)
		(pad "2" smd rect
			(at -0.2667 0 180)
			(size 0.3048 0.381)
			(layers "B.Cu" "B.Mask" "B.Paste")
			(net "GND")
		)
	)
	(footprint ""
		(layer "B.Cu")
		(at 273.253454 -190.94831 180)
		(property "Reference" "R295"
			(at 0 0 0)
			(layer "B.SilkS")
			(hide yes)
			(effects
				(font
					(size 1.27 1.27)
				)
				(justify mirror)
			)
		)
		(property "Value" ""
			(at 0 0 0)
			(layer "B.Fab")
			(effects
				(font
					(size 1.27 1.27)
				)
				(justify mirror)
			)
		)
		(duplicate_pad_numbers_are_jumpers no)
		(fp_line
			(start 0.7874 0.4064)
			(end 0.7874 -0.4064)
			(stroke
				(width 0.1524)
				(type default)
			)
			(layer "B.SilkS")
		)
		(fp_line
			(start 0.7874 -0.4064)
			(end -0.7874 -0.4064)
			(stroke
				(width 0.1524)
				(type default)
			)
			(layer "B.SilkS")
		)
		(fp_line
			(start -0.7874 0.4064)
			(end 0.7874 0.4064)
			(stroke
				(width 0.1524)
				(type default)
			)
			(layer "B.SilkS")
		)
		(fp_line
			(start -0.7874 -0.4064)
			(end -0.7874 0.4064)
			(stroke
				(width 0.1524)
				(type default)
			)
			(layer "B.SilkS")
		)
		(fp_line
			(start 0.67945 0.3048)
			(end 0.67945 -0.305054)
			(stroke
				(width 0.1)
				(type default)
			)
			(layer "B.Fab")
		)
		(fp_line
			(start 0.67945 -0.305054)
			(end 0.12065 -0.305054)
			(stroke
				(width 0.1)
				(type default)
			)
			(layer "B.Fab")
		)
		(fp_line
			(start 0.12065 0.3048)
			(end 0.67945 0.3048)
			(stroke
				(width 0.1)
				(type default)
			)
			(layer "B.Fab")
		)
		(fp_line
			(start 0.12065 0.2794)
			(end 0.12065 0.3048)
			(stroke
				(width 0.1)
				(type default)
			)
			(layer "B.Fab")
		)
		(fp_line
			(start 0.12065 -0.2794)
			(end -0.12065 -0.2794)
			(stroke
				(width 0.1)
				(type default)
			)
			(layer "B.Fab")
		)
		(fp_line
			(start 0.12065 -0.305054)
			(end 0.12065 -0.2794)
			(stroke
				(width 0.1)
				(type default)
			)
			(layer "B.Fab")
		)
		(fp_line
			(start -0.120396 0.3048)
			(end -0.120396 0.2794)
			(stroke
				(width 0.1)
				(type default)
			)
			(layer "B.Fab")
		)
		(fp_line
			(start -0.120396 0.2794)
			(end 0.12065 0.2794)
			(stroke
				(width 0.1)
				(type default)
			)
			(layer "B.Fab")
		)
		(fp_line
			(start -0.12065 -0.2794)
			(end -0.12065 -0.3048)
			(stroke
				(width 0.1)
				(type default)
			)
			(layer "B.Fab")
		)
		(fp_line
			(start -0.12065 -0.3048)
			(end -0.67945 -0.3048)
			(stroke
				(width 0.1)
				(type default)
			)
			(layer "B.Fab")
		)
		(fp_line
			(start -0.67945 0.3048)
			(end -0.120396 0.3048)
			(stroke
				(width 0.1)
				(type default)
			)
			(layer "B.Fab")
		)
		(fp_line
			(start -0.67945 -0.3048)
			(end -0.67945 0.3048)
			(stroke
				(width 0.1)
				(type default)
			)
			(layer "B.Fab")
		)
		(pad "1" smd circle
			(at 0.40005 0)
			(size 0 0)
			(layers "B.Cu" "B.Mask" "B.Paste")
			(net "PWRGD_CHE_CPU0_DIMM")
		)
		(pad "2" smd circle
			(at -0.40005 0)
			(size 0 0)
			(layers "B.Cu" "B.Mask" "B.Paste")
			(net "PWRGD_CHAF_CPU0")
		)
	)
	(footprint ""
		(layer "B.Cu")
		(at 111.125 -413.004)
		(property "Reference" "R585"
			(at 0 0 0)
			(layer "B.SilkS")
			(hide yes)
			(effects
				(font
					(size 1.27 1.27)
				)
				(justify mirror)
			)
		)
		(property "Value" ""
			(at 0 0 0)
			(layer "B.Fab")
			(effects
				(font
					(size 1.27 1.27)
				)
				(justify mirror)
			)
		)
		(duplicate_pad_numbers_are_jumpers no)
		(fp_line
			(start -0.7874 -0.4064)
			(end -0.7874 0.4064)
			(stroke
				(width 0.1524)
				(type default)
			)
			(layer "B.SilkS")
		)
		(fp_line
			(start -0.7874 0.4064)
			(end 0.7874 0.4064)
			(stroke
				(width 0.1524)
				(type default)
			)
			(layer "B.SilkS")
		)
		(fp_line
			(start 0.7874 -0.4064)
			(end -0.7874 -0.4064)
			(stroke
				(width 0.1524)
				(type default)
			)
			(layer "B.SilkS")
		)
		(fp_line
			(start 0.7874 0.4064)
			(end 0.7874 -0.4064)
			(stroke
				(width 0.1524)
				(type default)
			)
			(layer "B.SilkS")
		)
		(fp_line
			(start -0.67945 -0.3048)
			(end -0.67945 0.3048)
			(stroke
				(width 0.1)
				(type default)
			)
			(layer "B.Fab")
		)
		(fp_line
			(start -0.67945 0.3048)
			(end -0.120396 0.3048)
			(stroke
				(width 0.1)
				(type default)
			)
			(layer "B.Fab")
		)
		(fp_line
			(start -0.12065 -0.3048)
			(end -0.67945 -0.3048)
			(stroke
				(width 0.1)
				(type default)
			)
			(layer "B.Fab")
		)
		(fp_line
			(start -0.12065 -0.2794)
			(end -0.12065 -0.3048)
			(stroke
				(width 0.1)
				(type default)
			)
			(layer "B.Fab")
		)
		(fp_line
			(start -0.120396 0.2794)
			(end 0.12065 0.2794)
			(stroke
				(width 0.1)
				(type default)
			)
			(layer "B.Fab")
		)
		(fp_line
			(start -0.120396 0.3048)
			(end -0.120396 0.2794)
			(stroke
				(width 0.1)
				(type default)
			)
			(layer "B.Fab")
		)
		(fp_line
			(start 0.12065 -0.305054)
			(end 0.12065 -0.2794)
			(stroke
				(width 0.1)
				(type default)
			)
			(layer "B.Fab")
		)
		(fp_line
			(start 0.12065 -0.2794)
			(end -0.12065 -0.2794)
			(stroke
				(width 0.1)
				(type default)
			)
			(layer "B.Fab")
		)
		(fp_line
			(start 0.12065 0.2794)
			(end 0.12065 0.3048)
			(stroke
				(width 0.1)
				(type default)
			)
			(layer "B.Fab")
		)
		(fp_line
			(start 0.12065 0.3048)
			(end 0.67945 0.3048)
			(stroke
				(width 0.1)
				(type default)
			)
			(layer "B.Fab")
		)
		(fp_line
			(start 0.67945 -0.305054)
			(end 0.12065 -0.305054)
			(stroke
				(width 0.1)
				(type default)
			)
			(layer "B.Fab")
		)
		(fp_line
			(start 0.67945 0.3048)
			(end 0.67945 -0.305054)
			(stroke
				(width 0.1)
				(type default)
			)
			(layer "B.Fab")
		)
		(pad "1" smd circle
			(at 0.40005 0 180)
			(size 0 0)
			(layers "B.Cu" "B.Mask" "B.Paste")
			(net "CLK_9ZXL045_P1_HIBW")
		)
		(pad "2" smd circle
			(at -0.40005 0 180)
			(size 0 0)
			(layers "B.Cu" "B.Mask" "B.Paste")
			(net "GND")
		)
	)
	(footprint ""
		(layer "B.Cu")
		(at 346.518992 -257.930142 180)
		(property "Reference" "C2618"
			(at 0 0 0)
			(layer "B.SilkS")
			(hide yes)
			(effects
				(font
					(size 1.27 1.27)
				)
				(justify mirror)
			)
		)
		(property "Value" ""
			(at 0 0 0)
			(layer "B.Fab")
			(effects
				(font
					(size 1.27 1.27)
				)
				(justify mirror)
			)
		)
		(duplicate_pad_numbers_are_jumpers no)
		(fp_line
			(start 0.7874 0.4064)
			(end 0.7874 -0.4064)
			(stroke
				(width 0.1524)
				(type default)
			)
			(layer "B.SilkS")
		)
		(fp_line
			(start 0.7874 -0.4064)
			(end -0.7874 -0.4064)
			(stroke
				(width 0.1524)
				(type default)
			)
			(layer "B.SilkS")
		)
		(fp_line
			(start -0.7874 0.4064)
			(end 0.7874 0.4064)
			(stroke
				(width 0.1524)
				(type default)
			)
			(layer "B.SilkS")
		)
		(fp_line
			(start -0.7874 -0.4064)
			(end -0.7874 0.4064)
			(stroke
				(width 0.1524)
				(type default)
			)
			(layer "B.SilkS")
		)
		(fp_line
			(start 0.67945 0.3048)
			(end 0.67945 -0.305054)
			(stroke
				(width 0.1)
				(type default)
			)
			(layer "B.Fab")
		)
		(fp_line
			(start 0.67945 -0.305054)
			(end 0.12065 -0.305054)
			(stroke
				(width 0.1)
				(type default)
			)
			(layer "B.Fab")
		)
		(fp_line
			(start 0.12065 0.3048)
			(end 0.67945 0.3048)
			(stroke
				(width 0.1)
				(type default)
			)
			(layer "B.Fab")
		)
		(fp_line
			(start 0.12065 0.2794)
			(end 0.12065 0.3048)
			(stroke
				(width 0.1)
				(type default)
			)
			(layer "B.Fab")
		)
		(fp_line
			(start 0.12065 -0.2794)
			(end -0.12065 -0.2794)
			(stroke
				(width 0.1)
				(type default)
			)
			(layer "B.Fab")
		)
		(fp_line
			(start 0.12065 -0.305054)
			(end 0.12065 -0.2794)
			(stroke
				(width 0.1)
				(type default)
			)
			(layer "B.Fab")
		)
		(fp_line
			(start -0.120396 0.3048)
			(end -0.120396 0.2794)
			(stroke
				(width 0.1)
				(type default)
			)
			(layer "B.Fab")
		)
		(fp_line
			(start -0.120396 0.2794)
			(end 0.12065 0.2794)
			(stroke
				(width 0.1)
				(type default)
			)
			(layer "B.Fab")
		)
		(fp_line
			(start -0.12065 -0.2794)
			(end -0.12065 -0.3048)
			(stroke
				(width 0.1)
				(type default)
			)
			(layer "B.Fab")
		)
		(fp_line
			(start -0.12065 -0.3048)
			(end -0.67945 -0.3048)
			(stroke
				(width 0.1)
				(type default)
			)
			(layer "B.Fab")
		)
		(fp_line
			(start -0.67945 0.3048)
			(end -0.120396 0.3048)
			(stroke
				(width 0.1)
				(type default)
			)
			(layer "B.Fab")
		)
		(fp_line
			(start -0.67945 -0.3048)
			(end -0.67945 0.3048)
			(stroke
				(width 0.1)
				(type default)
			)
			(layer "B.Fab")
		)
		(pad "1" smd circle
			(at 0.40005 0)
			(size 0 0)
			(layers "B.Cu" "B.Mask" "B.Paste")
			(net "PVDDIO_P0")
		)
		(pad "2" smd circle
			(at -0.40005 0)
			(size 0 0)
			(layers "B.Cu" "B.Mask" "B.Paste")
			(net "GND")
		)
	)
	(footprint ""
		(layer "B.Cu")
		(at 83.50631 -386.766562 90)
		(property "Reference" "C294"
			(at 0 0 90)
			(layer "B.SilkS")
			(hide yes)
			(effects
				(font
					(size 1.27 1.27)
				)
				(justify mirror)
			)
		)
		(property "Value" ""
			(at 0 0 90)
			(layer "B.Fab")
			(effects
				(font
					(size 1.27 1.27)
				)
				(justify mirror)
			)
		)
		(duplicate_pad_numbers_are_jumpers no)
		(fp_line
			(start 0.299974 -0.150114)
			(end -0.299974 -0.150114)
			(stroke
				(width 0.1)
				(type default)
			)
			(layer "B.Fab")
		)
		(fp_line
			(start -0.299974 -0.150114)
			(end -0.299974 0.150114)
			(stroke
				(width 0.1)
				(type default)
			)
			(layer "B.Fab")
		)
		(fp_line
			(start 0.299974 0.150114)
			(end 0.299974 -0.150114)
			(stroke
				(width 0.1)
				(type default)
			)
			(layer "B.Fab")
		)
		(fp_line
			(start -0.299974 0.150114)
			(end 0.299974 0.150114)
			(stroke
				(width 0.1)
				(type default)
			)
			(layer "B.Fab")
		)
		(pad "1" smd rect
			(at 0.2667 0 270)
			(size 0.3048 0.381)
			(layers "B.Cu" "B.Mask" "B.Paste")
			(net "P0V9_CPU1_RT1_2A")
		)
		(pad "2" smd rect
			(at -0.2667 0 270)
			(size 0.3048 0.381)
			(layers "B.Cu" "B.Mask" "B.Paste")
			(net "GND")
		)
	)
)
